-- pcdb file, Rev:1.0 written by Allegro Design Entry HDL 16.5-S008 (v16-5-13Y) 10/18/2011 on Tue Oct 25 14:25:02 2011
#ISCELL
  mstr_standard drawing *
  *
#ISCELL
  mstr_standard synonym *
  page1_4p
